#ISCELL
  mstr_symbols intel_corp_bpage *
  *
#ISCELL
  mstr_symbols gnd *
  page242_i1
#ISCELL
  mstr_symbols gnd *
  page242_i10
#CELL
  mstr_discrete cap *
  page242_i11
#CELL
  mstr_discrete cap *
  page242_i15
#ISCELL
  mstr_symbols pvddq_abc *
  page242_i26
#ISCELL
  mstr_symbols gnd *
  page242_i27
#ISCELL
  mstr_symbols pvddq_def *
  page242_i29
#ISCELL
  mstr_symbols pvddq_abc *
  page242_i3
#ISCELL
  mstr_symbols gnd *
  page242_i33
#ISCELL
  mstr_symbols pvddq_def *
  page242_i35
#ISCELL
  mstr_symbols gnd *
  page242_i36
#CELL
  mstr_discrete cap *
  page242_i37
#CELL
  mstr_discrete cap *
  page242_i41
#ISCELL
  mstr_symbols pvddq_def *
  page242_i50
#CELL
  dev_discrete cap_a *
  page242_i53
#CELL
  dev_discrete cap_a *
  page242_i54
#CELL
  dev_discrete cap_a *
  page242_i55
#CELL
  dev_discrete cap_a *
  page242_i56
#CELL
  dev_discrete cap_a *
  page242_i57
#CELL
  dev_discrete cap_a *
  page242_i58
#CELL
  dev_discrete cap_a *
  page242_i59
#CELL
  dev_discrete cap_a *
  page242_i60
#CELL
  dev_discrete cap_a *
  page242_i61
#CELL
  dev_discrete cap_a *
  page242_i62
#CELL
  dev_discrete cap_a *
  page242_i63
#CELL
  dev_discrete cap_a *
  page242_i64
#CELL
  dev_discrete cap_a *
  page242_i65
#CELL
  dev_discrete cap_a *
  page242_i66
#CELL
  dev_discrete cap_a *
  page242_i67
#CELL
  dev_discrete cap_a *
  page242_i68
#CELL
  dev_discrete cap_a *
  page242_i69
#ISCELL
  mstr_symbols gnd *
  page242_i7
#CELL
  dev_discrete cap_a *
  page242_i70
#CELL
  dev_discrete cap_a *
  page242_i71
#CELL
  dev_discrete cap_a *
  page242_i72
#CELL
  dev_discrete cap_a *
  page242_i73
#CELL
  dev_discrete cap_a *
  page242_i74
#CELL
  dev_discrete cap_a *
  page242_i75
#CELL
  dev_discrete cap_a *
  page242_i76
#CELL
  dev_discrete cap_a *
  page242_i77
#CELL
  dev_discrete cap_a *
  page242_i78
#CELL
  dev_discrete cap_a *
  page242_i79
#CELL
  dev_discrete cap_a *
  page242_i80
#CELL
  dev_discrete cap_a *
  page242_i81
#CELL
  dev_discrete cap_a *
  page242_i82
#CELL
  dev_discrete cap_a *
  page242_i83
#CELL
  dev_discrete cap_a *
  page242_i84
#CELL
  dev_discrete cap_a *
  page242_i85
#CELL
  dev_discrete cap_a *
  page242_i86
#CELL
  dev_discrete cap_a *
  page242_i87
#CELL
  dev_discrete cap_a *
  page242_i88
#ISCELL
  mstr_symbols pvddq_abc *
  page242_i9
